(kicad_pcb
	(version 20260206)
	(generator "pcbnew")
	(generator_version "10.0")
	(general
		(thickness 1.6)
		(legacy_teardrops no)
	)
	(paper "A4")
	(title_block
		(title "04192023_DAF0TMB3IC0_F0TG_MB_C_brd_V02_OCP.brd")
		(comment 1 "Grand Teton / footprints 662-668 of 8354")
	)
	(layers
		(0 "F.Cu" signal "TOP")
		(4 "In1.Cu" signal "GND")
		(6 "In2.Cu" signal "IN1")
		(8 "In3.Cu" signal "GND1")
		(10 "In4.Cu" signal "IN2")
		(12 "In5.Cu" signal "GND2")
		(14 "In6.Cu" signal "IN3")
		(16 "In7.Cu" signal "GND3")
		(18 "In8.Cu" signal "VCC")
		(20 "In9.Cu" signal "VCC1")
		(22 "In10.Cu" signal "GND4")
		(24 "In11.Cu" signal "IN4")
		(26 "In12.Cu" signal "GND5")
		(28 "In13.Cu" signal "IN5")
		(30 "In14.Cu" signal "GND6")
		(32 "In15.Cu" signal "IN6")
		(34 "In16.Cu" signal "GND7")
		(2 "B.Cu" signal "BOTTOM")
		(9 "F.Adhes" user "F.Adhesive")
		(11 "B.Adhes" user "B.Adhesive")
		(13 "F.Paste" user "Package Geometry/Pastemask Top")
		(15 "B.Paste" user "Package Geometry/Pastemask Bottom")
		(5 "F.SilkS" user "Ref Des/Silkscreen Top")
		(7 "B.SilkS" user "Ref Des/Silkscreen Bottom")
		(1 "F.Mask" user "Board Geometry/Soldermask Top")
		(3 "B.Mask" user "Board Geometry/Soldermask Bottom")
		(17 "Dwgs.User" user "User.Drawings")
		(19 "Cmts.User" user "User.Comments")
		(21 "Eco1.User" user "User.Eco1")
		(23 "Eco2.User" user "User.Eco2")
		(25 "Edge.Cuts" user "Board Geometry/Outline")
		(27 "Margin" user)
		(31 "F.CrtYd" user "Package Geometry/Place Bound Top")
		(29 "B.CrtYd" user "Package Geometry/Place Bound Bottom")
		(35 "F.Fab" user "Ref Des/Assembly Top")
		(33 "B.Fab" user "Ref Des/Assembly Bottom")
	)
	(footprint ""
		(layer "F.Cu")
		(at 291.144452 -124.414026)
		(property "Reference" "C106"
			(at 0 0 0)
			(layer "F.SilkS")
			(hide yes)
			(effects
				(font
					(size 1.27 1.27)
				)
			)
		)
		(property "Value" ""
			(at 0 0 0)
			(layer "F.Fab")
			(effects
				(font
					(size 1.27 1.27)
				)
			)
		)
		(duplicate_pad_numbers_are_jumpers no)
		(fp_line
			(start -0.7874 -0.4064)
			(end 0.7874 -0.4064)
			(stroke
				(width 0.1524)
				(type default)
			)
			(layer "F.SilkS")
		)
		(fp_line
			(start -0.7874 0.4064)
			(end -0.7874 -0.4064)
			(stroke
				(width 0.1524)
				(type default)
			)
			(layer "F.SilkS")
		)
		(fp_line
			(start 0.7874 -0.4064)
			(end 0.7874 0.4064)
			(stroke
				(width 0.1524)
				(type default)
			)
			(layer "F.SilkS")
		)
		(fp_line
			(start 0.7874 0.4064)
			(end -0.7874 0.4064)
			(stroke
				(width 0.1524)
				(type default)
			)
			(layer "F.SilkS")
		)
		(fp_line
			(start -0.67945 -0.305054)
			(end -0.12065 -0.305054)
			(stroke
				(width 0.1)
				(type default)
			)
			(layer "F.Fab")
		)
		(fp_line
			(start -0.67945 0.3048)
			(end -0.67945 -0.305054)
			(stroke
				(width 0.1)
				(type default)
			)
			(layer "F.Fab")
		)
		(fp_line
			(start -0.12065 -0.305054)
			(end -0.12065 -0.2794)
			(stroke
				(width 0.1)
				(type default)
			)
			(layer "F.Fab")
		)
		(fp_line
			(start -0.12065 -0.2794)
			(end 0.12065 -0.2794)
			(stroke
				(width 0.1)
				(type default)
			)
			(layer "F.Fab")
		)
		(fp_line
			(start -0.12065 0.2794)
			(end -0.12065 0.3048)
			(stroke
				(width 0.1)
				(type default)
			)
			(layer "F.Fab")
		)
		(fp_line
			(start -0.12065 0.3048)
			(end -0.67945 0.3048)
			(stroke
				(width 0.1)
				(type default)
			)
			(layer "F.Fab")
		)
		(fp_line
			(start 0.120396 0.2794)
			(end -0.12065 0.2794)
			(stroke
				(width 0.1)
				(type default)
			)
			(layer "F.Fab")
		)
		(fp_line
			(start 0.120396 0.3048)
			(end 0.120396 0.2794)
			(stroke
				(width 0.1)
				(type default)
			)
			(layer "F.Fab")
		)
		(fp_line
			(start 0.12065 -0.3048)
			(end 0.67945 -0.3048)
			(stroke
				(width 0.1)
				(type default)
			)
			(layer "F.Fab")
		)
		(fp_line
			(start 0.12065 -0.2794)
			(end 0.12065 -0.3048)
			(stroke
				(width 0.1)
				(type default)
			)
			(layer "F.Fab")
		)
		(fp_line
			(start 0.67945 -0.3048)
			(end 0.67945 0.3048)
			(stroke
				(width 0.1)
				(type default)
			)
			(layer "F.Fab")
		)
		(fp_line
			(start 0.67945 0.3048)
			(end 0.120396 0.3048)
			(stroke
				(width 0.1)
				(type default)
			)
			(layer "F.Fab")
		)
		(pad "1" smd circle
			(at -0.40005 0)
			(size 0 0)
			(layers "F.Cu" "F.Mask" "F.Paste")
			(net "P3V3_AUX")
		)
		(pad "2" smd circle
			(at 0.40005 0)
			(size 0 0)
			(layers "F.Cu" "F.Mask" "F.Paste")
			(net "GND")
		)
	)
	(footprint ""
		(layer "F.Cu")
		(at 435.102 -171.4881 -90)
		(property "Reference" "R1333"
			(at 0 0 270)
			(layer "F.SilkS")
			(hide yes)
			(effects
				(font
					(size 1.27 1.27)
				)
			)
		)
		(property "Value" ""
			(at 0 0 270)
			(layer "F.Fab")
			(effects
				(font
					(size 1.27 1.27)
				)
			)
		)
		(duplicate_pad_numbers_are_jumpers no)
		(fp_line
			(start -0.7874 0.4064)
			(end -0.7874 -0.4064)
			(stroke
				(width 0.1524)
				(type default)
			)
			(layer "F.SilkS")
		)
		(fp_line
			(start 0.7874 0.4064)
			(end -0.7874 0.4064)
			(stroke
				(width 0.1524)
				(type default)
			)
			(layer "F.SilkS")
		)
		(fp_line
			(start -0.7874 -0.4064)
			(end 0.7874 -0.4064)
			(stroke
				(width 0.1524)
				(type default)
			)
			(layer "F.SilkS")
		)
		(fp_line
			(start 0.7874 -0.4064)
			(end 0.7874 0.4064)
			(stroke
				(width 0.1524)
				(type default)
			)
			(layer "F.SilkS")
		)
		(fp_line
			(start -0.67945 0.3048)
			(end -0.67945 -0.305054)
			(stroke
				(width 0.1)
				(type default)
			)
			(layer "F.Fab")
		)
		(fp_line
			(start -0.12065 0.3048)
			(end -0.67945 0.3048)
			(stroke
				(width 0.1)
				(type default)
			)
			(layer "F.Fab")
		)
		(fp_line
			(start 0.120396 0.3048)
			(end 0.120396 0.2794)
			(stroke
				(width 0.1)
				(type default)
			)
			(layer "F.Fab")
		)
		(fp_line
			(start 0.67945 0.3048)
			(end 0.120396 0.3048)
			(stroke
				(width 0.1)
				(type default)
			)
			(layer "F.Fab")
		)
		(fp_line
			(start -0.12065 0.2794)
			(end -0.12065 0.3048)
			(stroke
				(width 0.1)
				(type default)
			)
			(layer "F.Fab")
		)
		(fp_line
			(start 0.120396 0.2794)
			(end -0.12065 0.2794)
			(stroke
				(width 0.1)
				(type default)
			)
			(layer "F.Fab")
		)
		(fp_line
			(start -0.12065 -0.2794)
			(end 0.12065 -0.2794)
			(stroke
				(width 0.1)
				(type default)
			)
			(layer "F.Fab")
		)
		(fp_line
			(start 0.12065 -0.2794)
			(end 0.12065 -0.3048)
			(stroke
				(width 0.1)
				(type default)
			)
			(layer "F.Fab")
		)
		(fp_line
			(start 0.12065 -0.3048)
			(end 0.67945 -0.3048)
			(stroke
				(width 0.1)
				(type default)
			)
			(layer "F.Fab")
		)
		(fp_line
			(start 0.67945 -0.3048)
			(end 0.67945 0.3048)
			(stroke
				(width 0.1)
				(type default)
			)
			(layer "F.Fab")
		)
		(fp_line
			(start -0.67945 -0.305054)
			(end -0.12065 -0.305054)
			(stroke
				(width 0.1)
				(type default)
			)
			(layer "F.Fab")
		)
		(fp_line
			(start -0.12065 -0.305054)
			(end -0.12065 -0.2794)
			(stroke
				(width 0.1)
				(type default)
			)
			(layer "F.Fab")
		)
		(pad "1" smd rect
			(at -0.40005 0 90)
			(size 0.4572 0.508)
			(layers "F.Cu" "F.Mask" "F.Paste")
			(net "I3C_SPD_DDRGL_CPU0_BYPASS_SDA")
		)
		(pad "2" smd rect
			(at 0.40005 0 90)
			(size 0.4572 0.508)
			(layers "F.Cu" "F.Mask" "F.Paste")
			(net "I3C_SPD_DDRGL_CPU0_SDA")
		)
	)
	(footprint ""
		(layer "F.Cu")
		(at 178.8922 -96.103948 90)
		(property "Reference" "R235"
			(at 0 0 90)
			(layer "F.SilkS")
			(hide yes)
			(effects
				(font
					(size 1.27 1.27)
				)
			)
		)
		(property "Value" ""
			(at 0 0 90)
			(layer "F.Fab")
			(effects
				(font
					(size 1.27 1.27)
				)
			)
		)
		(duplicate_pad_numbers_are_jumpers no)
		(fp_line
			(start 0.7874 -0.4064)
			(end 0.7874 0.4064)
			(stroke
				(width 0.1524)
				(type default)
			)
			(layer "F.SilkS")
		)
		(fp_line
			(start -0.7874 -0.4064)
			(end 0.7874 -0.4064)
			(stroke
				(width 0.1524)
				(type default)
			)
			(layer "F.SilkS")
		)
		(fp_line
			(start 0.7874 0.4064)
			(end -0.7874 0.4064)
			(stroke
				(width 0.1524)
				(type default)
			)
			(layer "F.SilkS")
		)
		(fp_line
			(start -0.7874 0.4064)
			(end -0.7874 -0.4064)
			(stroke
				(width 0.1524)
				(type default)
			)
			(layer "F.SilkS")
		)
		(fp_line
			(start -0.12065 -0.305054)
			(end -0.12065 -0.2794)
			(stroke
				(width 0.1)
				(type default)
			)
			(layer "F.Fab")
		)
		(fp_line
			(start -0.67945 -0.305054)
			(end -0.12065 -0.305054)
			(stroke
				(width 0.1)
				(type default)
			)
			(layer "F.Fab")
		)
		(fp_line
			(start 0.67945 -0.3048)
			(end 0.67945 0.3048)
			(stroke
				(width 0.1)
				(type default)
			)
			(layer "F.Fab")
		)
		(fp_line
			(start 0.12065 -0.3048)
			(end 0.67945 -0.3048)
			(stroke
				(width 0.1)
				(type default)
			)
			(layer "F.Fab")
		)
		(fp_line
			(start 0.12065 -0.2794)
			(end 0.12065 -0.3048)
			(stroke
				(width 0.1)
				(type default)
			)
			(layer "F.Fab")
		)
		(fp_line
			(start -0.12065 -0.2794)
			(end 0.12065 -0.2794)
			(stroke
				(width 0.1)
				(type default)
			)
			(layer "F.Fab")
		)
		(fp_line
			(start 0.120396 0.2794)
			(end -0.12065 0.2794)
			(stroke
				(width 0.1)
				(type default)
			)
			(layer "F.Fab")
		)
		(fp_line
			(start -0.12065 0.2794)
			(end -0.12065 0.3048)
			(stroke
				(width 0.1)
				(type default)
			)
			(layer "F.Fab")
		)
		(fp_line
			(start 0.67945 0.3048)
			(end 0.120396 0.3048)
			(stroke
				(width 0.1)
				(type default)
			)
			(layer "F.Fab")
		)
		(fp_line
			(start 0.120396 0.3048)
			(end 0.120396 0.2794)
			(stroke
				(width 0.1)
				(type default)
			)
			(layer "F.Fab")
		)
		(fp_line
			(start -0.12065 0.3048)
			(end -0.67945 0.3048)
			(stroke
				(width 0.1)
				(type default)
			)
			(layer "F.Fab")
		)
		(fp_line
			(start -0.67945 0.3048)
			(end -0.67945 -0.305054)
			(stroke
				(width 0.1)
				(type default)
			)
			(layer "F.Fab")
		)
		(pad "1" smd circle
			(at -0.40005 0 90)
			(size 0 0)
			(layers "F.Cu" "F.Mask" "F.Paste")
			(net "CPU1_XTRIG_L7")
		)
		(pad "2" smd circle
			(at 0.40005 0 90)
			(size 0 0)
			(layers "F.Cu" "F.Mask" "F.Paste")
			(net "FM_CPU1_XTRIG_L7")
		)
	)
	(footprint ""
		(layer "F.Cu")
		(at 358.268524 -387.853428)
		(property "Reference" "C935"
			(at 0 0 0)
			(layer "F.SilkS")
			(hide yes)
			(effects
				(font
					(size 1.27 1.27)
				)
			)
		)
		(property "Value" ""
			(at 0 0 0)
			(layer "F.Fab")
			(effects
				(font
					(size 1.27 1.27)
				)
			)
		)
		(duplicate_pad_numbers_are_jumpers no)
		(fp_line
			(start -0.299974 -0.150114)
			(end 0.299974 -0.150114)
			(stroke
				(width 0.1)
				(type default)
			)
			(layer "F.Fab")
		)
		(fp_line
			(start -0.299974 0.150114)
			(end -0.299974 -0.150114)
			(stroke
				(width 0.1)
				(type default)
			)
			(layer "F.Fab")
		)
		(fp_line
			(start 0.299974 -0.150114)
			(end 0.299974 0.150114)
			(stroke
				(width 0.1)
				(type default)
			)
			(layer "F.Fab")
		)
		(fp_line
			(start 0.299974 0.150114)
			(end -0.299974 0.150114)
			(stroke
				(width 0.1)
				(type default)
			)
			(layer "F.Fab")
		)
		(pad "1" smd rect
			(at -0.2667 0)
			(size 0.3048 0.381)
			(layers "F.Cu" "F.Mask" "F.Paste")
			(net "P5E_CPU0_P1_TX_C_DP<15>")
		)
		(pad "2" smd rect
			(at 0.2667 0)
			(size 0.3048 0.381)
			(layers "F.Cu" "F.Mask" "F.Paste")
			(net "P5E_CPU0_P1_TX_DP<15>")
		)
	)
	(footprint ""
		(layer "F.Cu")
		(at 179.482242 -422.802304 -90)
		(property "Reference" "C1713"
			(at 0 0 270)
			(layer "F.SilkS")
			(hide yes)
			(effects
				(font
					(size 1.27 1.27)
				)
			)
		)
		(property "Value" ""
			(at 0 0 270)
			(layer "F.Fab")
			(effects
				(font
					(size 1.27 1.27)
				)
			)
		)
		(duplicate_pad_numbers_are_jumpers no)
		(fp_line
			(start -0.7874 0.4064)
			(end -0.7874 -0.4064)
			(stroke
				(width 0.1524)
				(type default)
			)
			(layer "F.SilkS")
		)
		(fp_line
			(start 0.7874 0.4064)
			(end -0.7874 0.4064)
			(stroke
				(width 0.1524)
				(type default)
			)
			(layer "F.SilkS")
		)
		(fp_line
			(start -0.7874 -0.4064)
			(end 0.7874 -0.4064)
			(stroke
				(width 0.1524)
				(type default)
			)
			(layer "F.SilkS")
		)
		(fp_line
			(start 0.7874 -0.4064)
			(end 0.7874 0.4064)
			(stroke
				(width 0.1524)
				(type default)
			)
			(layer "F.SilkS")
		)
		(fp_line
			(start -0.67945 0.3048)
			(end -0.67945 -0.305054)
			(stroke
				(width 0.1)
				(type default)
			)
			(layer "F.Fab")
		)
		(fp_line
			(start -0.12065 0.3048)
			(end -0.67945 0.3048)
			(stroke
				(width 0.1)
				(type default)
			)
			(layer "F.Fab")
		)
		(fp_line
			(start 0.120396 0.3048)
			(end 0.120396 0.2794)
			(stroke
				(width 0.1)
				(type default)
			)
			(layer "F.Fab")
		)
		(fp_line
			(start 0.67945 0.3048)
			(end 0.120396 0.3048)
			(stroke
				(width 0.1)
				(type default)
			)
			(layer "F.Fab")
		)
		(fp_line
			(start -0.12065 0.2794)
			(end -0.12065 0.3048)
			(stroke
				(width 0.1)
				(type default)
			)
			(layer "F.Fab")
		)
		(fp_line
			(start 0.120396 0.2794)
			(end -0.12065 0.2794)
			(stroke
				(width 0.1)
				(type default)
			)
			(layer "F.Fab")
		)
		(fp_line
			(start -0.12065 -0.2794)
			(end 0.12065 -0.2794)
			(stroke
				(width 0.1)
				(type default)
			)
			(layer "F.Fab")
		)
		(fp_line
			(start 0.12065 -0.2794)
			(end 0.12065 -0.3048)
			(stroke
				(width 0.1)
				(type default)
			)
			(layer "F.Fab")
		)
		(fp_line
			(start 0.12065 -0.3048)
			(end 0.67945 -0.3048)
			(stroke
				(width 0.1)
				(type default)
			)
			(layer "F.Fab")
		)
		(fp_line
			(start 0.67945 -0.3048)
			(end 0.67945 0.3048)
			(stroke
				(width 0.1)
				(type default)
			)
			(layer "F.Fab")
		)
		(fp_line
			(start -0.67945 -0.305054)
			(end -0.12065 -0.305054)
			(stroke
				(width 0.1)
				(type default)
			)
			(layer "F.Fab")
		)
		(fp_line
			(start -0.12065 -0.305054)
			(end -0.12065 -0.2794)
			(stroke
				(width 0.1)
				(type default)
			)
			(layer "F.Fab")
		)
		(pad "1" smd circle
			(at -0.40005 0 270)
			(size 0 0)
			(layers "F.Cu" "F.Mask" "F.Paste")
			(net "P3V3_AUX")
		)
		(pad "2" smd circle
			(at 0.40005 0 270)
			(size 0 0)
			(layers "F.Cu" "F.Mask" "F.Paste")
			(net "GND")
		)
	)
	(footprint ""
		(layer "F.Cu")
		(at 356.565962 -256.012188 90)
		(property "Reference" "C3895"
			(at 0 0 90)
			(layer "F.SilkS")
			(hide yes)
			(effects
				(font
					(size 1.27 1.27)
				)
			)
		)
		(property "Value" ""
			(at 0 0 90)
			(layer "F.Fab")
			(effects
				(font
					(size 1.27 1.27)
				)
			)
		)
		(duplicate_pad_numbers_are_jumpers no)
		(fp_line
			(start 0.7874 -0.4064)
			(end 0.7874 0.4064)
			(stroke
				(width 0.1524)
				(type default)
			)
			(layer "F.SilkS")
		)
		(fp_line
			(start -0.7874 -0.4064)
			(end 0.7874 -0.4064)
			(stroke
				(width 0.1524)
				(type default)
			)
			(layer "F.SilkS")
		)
		(fp_line
			(start 0.7874 0.4064)
			(end -0.7874 0.4064)
			(stroke
				(width 0.1524)
				(type default)
			)
			(layer "F.SilkS")
		)
		(fp_line
			(start -0.7874 0.4064)
			(end -0.7874 -0.4064)
			(stroke
				(width 0.1524)
				(type default)
			)
			(layer "F.SilkS")
		)
		(fp_line
			(start -0.12065 -0.305054)
			(end -0.12065 -0.2794)
			(stroke
				(width 0.1)
				(type default)
			)
			(layer "F.Fab")
		)
		(fp_line
			(start -0.67945 -0.305054)
			(end -0.12065 -0.305054)
			(stroke
				(width 0.1)
				(type default)
			)
			(layer "F.Fab")
		)
		(fp_line
			(start 0.67945 -0.3048)
			(end 0.67945 0.3048)
			(stroke
				(width 0.1)
				(type default)
			)
			(layer "F.Fab")
		)
		(fp_line
			(start 0.12065 -0.3048)
			(end 0.67945 -0.3048)
			(stroke
				(width 0.1)
				(type default)
			)
			(layer "F.Fab")
		)
		(fp_line
			(start 0.12065 -0.2794)
			(end 0.12065 -0.3048)
			(stroke
				(width 0.1)
				(type default)
			)
			(layer "F.Fab")
		)
		(fp_line
			(start -0.12065 -0.2794)
			(end 0.12065 -0.2794)
			(stroke
				(width 0.1)
				(type default)
			)
			(layer "F.Fab")
		)
		(fp_line
			(start 0.120396 0.2794)
			(end -0.12065 0.2794)
			(stroke
				(width 0.1)
				(type default)
			)
			(layer "F.Fab")
		)
		(fp_line
			(start -0.12065 0.2794)
			(end -0.12065 0.3048)
			(stroke
				(width 0.1)
				(type default)
			)
			(layer "F.Fab")
		)
		(fp_line
			(start 0.67945 0.3048)
			(end 0.120396 0.3048)
			(stroke
				(width 0.1)
				(type default)
			)
			(layer "F.Fab")
		)
		(fp_line
			(start 0.120396 0.3048)
			(end 0.120396 0.2794)
			(stroke
				(width 0.1)
				(type default)
			)
			(layer "F.Fab")
		)
		(fp_line
			(start -0.12065 0.3048)
			(end -0.67945 0.3048)
			(stroke
				(width 0.1)
				(type default)
			)
			(layer "F.Fab")
		)
		(fp_line
			(start -0.67945 0.3048)
			(end -0.67945 -0.305054)
			(stroke
				(width 0.1)
				(type default)
			)
			(layer "F.Fab")
		)
		(pad "1" smd circle
			(at -0.40005 0 90)
			(size 0 0)
			(layers "F.Cu" "F.Mask" "F.Paste")
			(net "PVDDCR_SOC_P0")
		)
		(pad "2" smd circle
			(at 0.40005 0 90)
			(size 0 0)
			(layers "F.Cu" "F.Mask" "F.Paste")
			(net "GND")
		)
	)
	(footprint ""
		(layer "F.Cu")
		(at 143.88084 -40.403526 90)
		(property "Reference" "C1859"
			(at 0 0 90)
			(layer "F.SilkS")
			(hide yes)
			(effects
				(font
					(size 1.27 1.27)
				)
			)
		)
		(property "Value" ""
			(at 0 0 90)
			(layer "F.Fab")
			(effects
				(font
					(size 1.27 1.27)
				)
			)
		)
		(duplicate_pad_numbers_are_jumpers no)
		(fp_line
			(start 0.7874 -0.4064)
			(end 0.7874 0.4064)
			(stroke
				(width 0.1524)
				(type default)
			)
			(layer "F.SilkS")
		)
		(fp_line
			(start -0.7874 -0.4064)
			(end 0.7874 -0.4064)
			(stroke
				(width 0.1524)
				(type default)
			)
			(layer "F.SilkS")
		)
		(fp_line
			(start 0.7874 0.4064)
			(end -0.7874 0.4064)
			(stroke
				(width 0.1524)
				(type default)
			)
			(layer "F.SilkS")
		)
		(fp_line
			(start -0.7874 0.4064)
			(end -0.7874 -0.4064)
			(stroke
				(width 0.1524)
				(type default)
			)
			(layer "F.SilkS")
		)
		(fp_line
			(start -0.12065 -0.305054)
			(end -0.12065 -0.2794)
			(stroke
				(width 0.1)
				(type default)
			)
			(layer "F.Fab")
		)
		(fp_line
			(start -0.67945 -0.305054)
			(end -0.12065 -0.305054)
			(stroke
				(width 0.1)
				(type default)
			)
			(layer "F.Fab")
		)
		(fp_line
			(start 0.67945 -0.3048)
			(end 0.67945 0.3048)
			(stroke
				(width 0.1)
				(type default)
			)
			(layer "F.Fab")
		)
		(fp_line
			(start 0.12065 -0.3048)
			(end 0.67945 -0.3048)
			(stroke
				(width 0.1)
				(type default)
			)
			(layer "F.Fab")
		)
		(fp_line
			(start 0.12065 -0.2794)
			(end 0.12065 -0.3048)
			(stroke
				(width 0.1)
				(type default)
			)
			(layer "F.Fab")
		)
		(fp_line
			(start -0.12065 -0.2794)
			(end 0.12065 -0.2794)
			(stroke
				(width 0.1)
				(type default)
			)
			(layer "F.Fab")
		)
		(fp_line
			(start 0.120396 0.2794)
			(end -0.12065 0.2794)
			(stroke
				(width 0.1)
				(type default)
			)
			(layer "F.Fab")
		)
		(fp_line
			(start -0.12065 0.2794)
			(end -0.12065 0.3048)
			(stroke
				(width 0.1)
				(type default)
			)
			(layer "F.Fab")
		)
		(fp_line
			(start 0.67945 0.3048)
			(end 0.120396 0.3048)
			(stroke
				(width 0.1)
				(type default)
			)
			(layer "F.Fab")
		)
		(fp_line
			(start 0.120396 0.3048)
			(end 0.120396 0.2794)
			(stroke
				(width 0.1)
				(type default)
			)
			(layer "F.Fab")
		)
		(fp_line
			(start -0.12065 0.3048)
			(end -0.67945 0.3048)
			(stroke
				(width 0.1)
				(type default)
			)
			(layer "F.Fab")
		)
		(fp_line
			(start -0.67945 0.3048)
			(end -0.67945 -0.305054)
			(stroke
				(width 0.1)
				(type default)
			)
			(layer "F.Fab")
		)
		(pad "1" smd circle
			(at -0.40005 0 90)
			(size 0 0)
			(layers "F.Cu" "F.Mask" "F.Paste")
			(net "P3V3_AUX")
		)
		(pad "2" smd circle
			(at 0.40005 0 90)
			(size 0 0)
			(layers "F.Cu" "F.Mask" "F.Paste")
			(net "GND")
		)
	)
)
